(kicad_pcb
	(version 20260206)
	(generator "pcbnew")
	(generator_version "10.0")
	(general
		(thickness 1.6)
		(legacy_teardrops no)
	)
	(paper "A4")
	(title_block
		(title "Wiwynn_Tioga_Pass_MB.brd")
		(comment 1 "Tioga Pass / footprints 2229-2233 of 4770")
	)
	(layers
		(0 "F.Cu" signal "TOP")
		(4 "In1.Cu" signal "L2GND")
		(6 "In2.Cu" signal "L3")
		(8 "In3.Cu" signal "L4GND")
		(10 "In4.Cu" signal "L5")
		(12 "In5.Cu" signal "L6GND")
		(14 "In6.Cu" signal "L7VCC")
		(16 "In7.Cu" signal "L8VCC")
		(18 "In8.Cu" signal "L9GND")
		(20 "In9.Cu" signal "L10")
		(22 "In10.Cu" signal "L11GND")
		(24 "In11.Cu" signal "L12")
		(26 "In12.Cu" signal "L13GND")
		(2 "B.Cu" signal "BOTTOM")
		(9 "F.Adhes" user "F.Adhesive")
		(11 "B.Adhes" user "B.Adhesive")
		(13 "F.Paste" user "Package Geometry/Pastemask Top")
		(15 "B.Paste" user "Package Geometry/Pastemask Bottom")
		(5 "F.SilkS" user "Ref Des/Silkscreen Top")
		(7 "B.SilkS" user "Ref Des/Silkscreen Bottom")
		(1 "F.Mask" user "Board Geometry/Soldermask Top")
		(3 "B.Mask" user "Board Geometry/Soldermask Bottom")
		(17 "Dwgs.User" user "User.Drawings")
		(19 "Cmts.User" user "User.Comments")
		(21 "Eco1.User" user "User.Eco1")
		(23 "Eco2.User" user "User.Eco2")
		(25 "Edge.Cuts" user "Board Geometry/Outline")
		(27 "Margin" user)
		(31 "F.CrtYd" user "Package Geometry/Place Bound Top")
		(29 "B.CrtYd" user "Package Geometry/Place Bound Bottom")
		(35 "F.Fab" user "Ref Des/Assembly Top")
		(33 "B.Fab" user "Ref Des/Assembly Bottom")
	)
	(footprint ""
		(layer "F.Cu")
		(at 440.817 -143.764 90)
		(property "Reference" "R25W161"
			(at -0.8382 -0.67818 90)
			(unlocked yes)
			(layer "F.SilkS")
			(effects
				(font
					(size 0.4064 0.254)
					(thickness 0.1524)
				)
				(justify left)
			)
		)
		(property "Value" ""
			(at 0 0 90)
			(layer "F.Fab")
			(effects
				(font
					(size 1.27 1.27)
				)
			)
		)
		(duplicate_pad_numbers_are_jumpers no)
		(fp_poly
			(pts
				(xy -0.2794 -0.1016) (xy 0.2794 -0.1016) (xy 0.2794 0.9906) (xy -0.2794 0.9906)
			)
			(stroke
				(width 0)
				(type default)
			)
			(fill no)
			(layer "F.CrtYd")
		)
		(fp_line
			(start 0.2794 -0.1016)
			(end -0.2794 -0.1016)
			(stroke
				(width 0.1)
				(type default)
			)
			(layer "F.Fab")
		)
		(fp_line
			(start -0.2794 -0.1016)
			(end -0.2794 0.9906)
			(stroke
				(width 0.1)
				(type default)
			)
			(layer "F.Fab")
		)
		(fp_line
			(start 0.2794 0.9906)
			(end 0.2794 -0.1016)
			(stroke
				(width 0.1)
				(type default)
			)
			(layer "F.Fab")
		)
		(fp_line
			(start -0.2794 0.9906)
			(end 0.2794 0.9906)
			(stroke
				(width 0.1)
				(type default)
			)
			(layer "F.Fab")
		)
		(pad "1" smd rect
			(at 0 0 90)
			(size 0.508 0.508)
			(layers "F.Cu" "F.Mask" "F.Paste")
			(net "P3V3_STBY")
		)
		(pad "2" smd rect
			(at 0 0.889 90)
			(size 0.508 0.508)
			(layers "F.Cu" "F.Mask" "F.Paste")
			(net "JTAG_BMC_BUF_TMS")
		)
		(zone
			(layer "F.Cu")
			(hatch none 0.5)
			(connect_pads
				(clearance 0)
			)
			(min_thickness 0.25)
			(keepout
				(tracks allowed)
				(vias not_allowed)
				(pads allowed)
				(copperpour not_allowed)
				(footprints allowed)
			)
			(placement
				(enabled no)
				(sheetname "")
			)
			(fill
				(thermal_gap 0.5)
				(thermal_bridge_width 0.5)
				(island_removal_mode 0)
			)
			(polygon
				(pts
					(xy 441.071 -143.51) (xy 441.071 -144.018) (xy 441.452 -144.018) (xy 441.452 -143.51)
				)
			)
		)
		(zone
			(layer "F.Cu")
			(hatch none 0.5)
			(connect_pads
				(clearance 0)
			)
			(min_thickness 0.25)
			(keepout
				(tracks not_allowed)
				(vias allowed)
				(pads allowed)
				(copperpour not_allowed)
				(footprints allowed)
			)
			(placement
				(enabled no)
				(sheetname "")
			)
			(fill
				(thermal_gap 0.5)
				(thermal_bridge_width 0.5)
				(island_removal_mode 0)
			)
			(polygon
				(pts
					(xy 441.452 -143.51) (xy 441.452 -144.018) (xy 441.071 -144.018) (xy 441.071 -143.51)
				)
			)
		)
	)
	(footprint ""
		(layer "F.Cu")
		(at 415.191194 -132.7404)
		(property "Reference" "J8B1"
			(at 1.59258 -3.68427 0)
			(unlocked yes)
			(layer "F.SilkS")
			(effects
				(font
					(size 0.7874 0.5842)
					(thickness 0.1524)
				)
				(justify left)
			)
		)
		(property "Value" ""
			(at 0 0 0)
			(layer "F.Fab")
			(effects
				(font
					(size 1.27 1.27)
				)
			)
		)
		(duplicate_pad_numbers_are_jumpers no)
		(fp_line
			(start -0.181102 -1.774952)
			(end 1.851914 -1.774952)
			(stroke
				(width 0.1524)
				(type default)
			)
			(layer "F.SilkS")
		)
		(fp_line
			(start -0.181102 -0.747014)
			(end -0.181102 -1.774952)
			(stroke
				(width 0.1524)
				(type default)
			)
			(layer "F.SilkS")
		)
		(fp_line
			(start -0.181102 12.77493)
			(end -0.181102 11.744452)
			(stroke
				(width 0.1524)
				(type default)
			)
			(layer "F.SilkS")
		)
		(fp_line
			(start 1.851914 12.77493)
			(end -0.181102 12.77493)
			(stroke
				(width 0.1524)
				(type default)
			)
			(layer "F.SilkS")
		)
		(fp_line
			(start 4.535424 -1.774952)
			(end 5.769102 -1.774952)
			(stroke
				(width 0.1524)
				(type default)
			)
			(layer "F.SilkS")
		)
		(fp_line
			(start 5.769102 -1.774952)
			(end 5.769102 -0.747014)
			(stroke
				(width 0.1524)
				(type default)
			)
			(layer "F.SilkS")
		)
		(fp_line
			(start 5.769102 11.744452)
			(end 5.769102 12.77493)
			(stroke
				(width 0.1524)
				(type default)
			)
			(layer "F.SilkS")
		)
		(fp_line
			(start 5.769102 12.77493)
			(end 4.535424 12.77493)
			(stroke
				(width 0.1524)
				(type default)
			)
			(layer "F.SilkS")
		)
		(fp_poly
			(pts
				(xy -1.325372 0.029718) (xy -2.595372 0.537718) (xy -2.595372 -0.478282)
			)
			(stroke
				(width 0)
				(type default)
			)
			(fill yes)
			(layer "F.SilkS")
		)
		(fp_poly
			(pts
				(xy -0.181102 -1.774952) (xy -0.181102 12.77493) (xy 5.769102 12.77493) (xy 5.769102 -1.774952)
			)
			(stroke
				(width 0)
				(type default)
			)
			(fill no)
			(layer "F.CrtYd")
		)
		(fp_line
			(start -0.181102 -1.774952)
			(end 5.769102 -1.774952)
			(stroke
				(width 0.1)
				(type default)
			)
			(layer "F.Fab")
		)
		(fp_line
			(start -0.181102 12.77493)
			(end -0.181102 -1.774952)
			(stroke
				(width 0.1)
				(type default)
			)
			(layer "F.Fab")
		)
		(fp_line
			(start 5.769102 -1.774952)
			(end 5.769102 12.77493)
			(stroke
				(width 0.1)
				(type default)
			)
			(layer "F.Fab")
		)
		(fp_line
			(start 5.769102 12.77493)
			(end -0.181102 12.77493)
			(stroke
				(width 0.1)
				(type default)
			)
			(layer "F.Fab")
		)
		(fp_poly
			(pts
				(xy -1.325372 0.029718) (xy -2.595372 -0.478282) (xy -2.595372 0.537718)
			)
			(stroke
				(width 0)
				(type default)
			)
			(fill yes)
			(layer "F.Fab")
		)
		(fp_text user "23"
			(at -2.31902 11.571224 0)
			(unlocked yes)
			(layer "F.SilkS")
			(effects
				(font
					(size 0.7874 0.5842)
					(thickness 0.1524)
				)
				(justify left)
			)
		)
		(fp_text user "2"
			(at 6.677406 1.16967 0)
			(unlocked yes)
			(layer "F.SilkS")
			(effects
				(font
					(size 0.7874 0.5842)
					(thickness 0.1524)
				)
				(justify left)
			)
		)
		(fp_text user "24"
			(at 6.884924 11.015218 0)
			(unlocked yes)
			(layer "F.SilkS")
			(effects
				(font
					(size 0.7874 0.5842)
					(thickness 0.1524)
				)
				(justify left)
			)
		)
		(fp_text user "23"
			(at -2.319274 11.573764 0)
			(unlocked yes)
			(layer "F.Fab")
			(effects
				(font
					(size 0.7874 0.5842)
					(thickness 0.1524)
				)
				(justify left)
			)
		)
		(fp_text user "24"
			(at 6.884924 11.012678 0)
			(unlocked yes)
			(layer "F.Fab")
			(effects
				(font
					(size 0.7874 0.5842)
					(thickness 0.1524)
				)
				(justify left)
			)
		)
		(pad "" np_thru_hole circle
			(at 0.89408 -0.849884)
			(size 0.254 0.254)
			(drill 0.5588)
			(layers "*.Cu" "*.Mask")
			(clearance 0.4699)
			(thermal_gap 0.4699)
		)
		(pad "" np_thru_hole circle
			(at 0.89408 11.850116)
			(size 0.254 0.254)
			(drill 0.5588)
			(layers "*.Cu" "*.Mask")
			(clearance 0.4699)
			(thermal_gap 0.4699)
		)
		(pad "1" smd rect
			(at 0 0)
			(size 1.6002 0.6096)
			(layers "F.Cu" "F.Mask" "F.Paste")
			(net "GND")
		)
		(pad "2" smd rect
			(at 5.588 0)
			(size 1.6002 0.6096)
			(layers "F.Cu" "F.Mask" "F.Paste")
			(net "SMB_HFI0_CPU0_LVC2_SCL")
		)
		(pad "3" smd rect
			(at 0 0.999998)
			(size 1.6002 0.6096)
			(layers "F.Cu" "F.Mask" "F.Paste")
			(net "FM_MODPRST_HFI0_CPU0_LVT2_N")
		)
		(pad "4" smd rect
			(at 5.588 0.999998)
			(size 1.6002 0.6096)
			(layers "F.Cu" "F.Mask" "F.Paste")
			(net "SMB_HFI0_CPU0_LVC2_SDA")
		)
		(pad "5" smd rect
			(at 0 1.999996)
			(size 1.6002 0.6096)
			(layers "F.Cu" "F.Mask" "F.Paste")
			(net "LED_HFI0_CPU0_N")
		)
		(pad "6" smd rect
			(at 5.588 1.999996)
			(size 1.6002 0.6096)
			(layers "F.Cu" "F.Mask" "F.Paste")
			(net "RST_HFI0_CPU0_LVT2_N")
		)
		(pad "7" smd rect
			(at 0 2.999994)
			(size 1.6002 0.6096)
			(layers "F.Cu" "F.Mask" "F.Paste")
			(net "GND")
		)
		(pad "8" smd rect
			(at 5.588 2.999994)
			(size 1.6002 0.6096)
			(layers "F.Cu" "F.Mask" "F.Paste")
			(net "IRQ_HFI0_CPU0_LVT2_N")
		)
		(pad "9" smd rect
			(at 0 3.999992)
			(size 1.6002 0.6096)
			(layers "F.Cu" "F.Mask" "F.Paste")
			(net "GND")
		)
		(pad "10" smd rect
			(at 5.588 3.999992)
			(size 1.6002 0.6096)
			(layers "F.Cu" "F.Mask" "F.Paste")
			(net "SMB_HFI1_CPU0_LVC2_SCL")
		)
		(pad "11" smd rect
			(at 0 4.99999)
			(size 1.6002 0.6096)
			(layers "F.Cu" "F.Mask" "F.Paste")
			(net "FM_MODPRST_HFI1_CPU0_LVT2_N")
		)
		(pad "12" smd rect
			(at 5.588 4.99999)
			(size 1.6002 0.6096)
			(layers "F.Cu" "F.Mask" "F.Paste")
			(net "SMB_HFI1_CPU0_LVC2_SDA")
		)
		(pad "13" smd rect
			(at 0 5.999988)
			(size 1.6002 0.6096)
			(layers "F.Cu" "F.Mask" "F.Paste")
			(net "LED_HFI1_CPU0_N")
		)
		(pad "14" smd rect
			(at 5.588 5.999988)
			(size 1.6002 0.6096)
			(layers "F.Cu" "F.Mask" "F.Paste")
			(net "RST_HFI1_CPU0_LVT2_N")
		)
		(pad "15" smd rect
			(at 0 6.999986)
			(size 1.6002 0.6096)
			(layers "F.Cu" "F.Mask" "F.Paste")
			(net "GND")
		)
		(pad "16" smd rect
			(at 5.588 6.999986)
			(size 1.6002 0.6096)
			(layers "F.Cu" "F.Mask" "F.Paste")
			(net "IRQ_HFI1_CPU0_LVT2_N")
		)
		(pad "17" smd rect
			(at 0 7.999984)
			(size 1.6002 0.6096)
			(layers "F.Cu" "F.Mask" "F.Paste")
			(net "TP_HFI_IO_CONN0_RSVD_17")
		)
		(pad "18" smd rect
			(at 5.588 7.999984)
			(size 1.6002 0.6096)
			(layers "F.Cu" "F.Mask" "F.Paste")
			(net "P3V3")
		)
		(pad "19" smd rect
			(at 0 8.999982)
			(size 1.6002 0.6096)
			(layers "F.Cu" "F.Mask" "F.Paste")
			(net "PWRGD_PVPP_ABC")
		)
		(pad "20" smd rect
			(at 5.588 8.999982)
			(size 1.6002 0.6096)
			(layers "F.Cu" "F.Mask" "F.Paste")
			(net "P3V3")
		)
		(pad "21" smd rect
			(at 0 9.99998)
			(size 1.6002 0.6096)
			(layers "F.Cu" "F.Mask" "F.Paste")
			(net "PVPP_ABC")
		)
		(pad "22" smd rect
			(at 5.588 9.99998)
			(size 1.6002 0.6096)
			(layers "F.Cu" "F.Mask" "F.Paste")
			(net "SMB_OCP_FRU_STBY_LVC3_SCL")
		)
		(pad "23" smd rect
			(at 0 10.999978)
			(size 1.6002 0.6096)
			(layers "F.Cu" "F.Mask" "F.Paste")
			(net "GND")
		)
		(pad "24" smd rect
			(at 5.588 10.999978)
			(size 1.6002 0.6096)
			(layers "F.Cu" "F.Mask" "F.Paste")
			(net "SMB_OCP_FRU_STBY_LVC3_SDA")
		)
		(pad "MP1" smd rect
			(at 3.19405 -1.325118)
			(size 1.8034 0.889)
			(layers "F.Cu" "F.Mask" "F.Paste")
			(net "GND")
		)
		(pad "MP2" smd rect
			(at 3.19405 12.325096)
			(size 1.8034 0.889)
			(layers "F.Cu" "F.Mask" "F.Paste")
			(net "GND")
		)
		(zone
			(layers "F.Cu" "B.Cu" "In1.Cu" "In2.Cu" "In3.Cu" "In4.Cu" "In5.Cu" "In6.Cu"
				"In7.Cu" "In8.Cu" "In9.Cu" "In10.Cu" "In11.Cu" "In12.Cu"
			)
			(hatch none 0.5)
			(connect_pads
				(clearance 0)
			)
			(min_thickness 0.25)
			(keepout
				(tracks not_allowed)
				(vias allowed)
				(pads allowed)
				(copperpour not_allowed)
				(footprints allowed)
			)
			(placement
				(enabled no)
				(sheetname "")
			)
			(fill
				(thermal_gap 0.5)
				(thermal_bridge_width 0.5)
				(island_removal_mode 0)
			)
			(polygon
				(pts
					(arc
						(start 416.68192 -133.590284)
						(mid 415.488628 -133.590284)
						(end 416.68192 -133.590284)
					)
				)
			)
		)
		(zone
			(layers "F.Cu" "B.Cu" "In1.Cu" "In2.Cu" "In3.Cu" "In4.Cu" "In5.Cu" "In6.Cu"
				"In7.Cu" "In8.Cu" "In9.Cu" "In10.Cu" "In11.Cu" "In12.Cu"
			)
			(hatch none 0.5)
			(connect_pads
				(clearance 0)
			)
			(min_thickness 0.25)
			(keepout
				(tracks not_allowed)
				(vias allowed)
				(pads allowed)
				(copperpour not_allowed)
				(footprints allowed)
			)
			(placement
				(enabled no)
				(sheetname "")
			)
			(fill
				(thermal_gap 0.5)
				(thermal_bridge_width 0.5)
				(island_removal_mode 0)
			)
			(polygon
				(pts
					(arc
						(start 416.68192 -120.890284)
						(mid 415.488628 -120.890284)
						(end 416.68192 -120.890284)
					)
				)
			)
		)
	)
	(footprint ""
		(layer "F.Cu")
		(at 450.723 -20.2692 -90)
		(property "Reference" "R9W12"
			(at -0.8382 -0.67818 270)
			(unlocked yes)
			(layer "F.SilkS")
			(effects
				(font
					(size 0.4064 0.254)
					(thickness 0.1524)
				)
				(justify left)
			)
		)
		(property "Value" ""
			(at 0 0 270)
			(layer "F.Fab")
			(effects
				(font
					(size 1.27 1.27)
				)
			)
		)
		(duplicate_pad_numbers_are_jumpers no)
		(fp_poly
			(pts
				(xy -0.2794 -0.1016) (xy 0.2794 -0.1016) (xy 0.2794 0.9906) (xy -0.2794 0.9906)
			)
			(stroke
				(width 0)
				(type default)
			)
			(fill no)
			(layer "F.CrtYd")
		)
		(fp_line
			(start -0.2794 0.9906)
			(end 0.2794 0.9906)
			(stroke
				(width 0.1)
				(type default)
			)
			(layer "F.Fab")
		)
		(fp_line
			(start 0.2794 0.9906)
			(end 0.2794 -0.1016)
			(stroke
				(width 0.1)
				(type default)
			)
			(layer "F.Fab")
		)
		(fp_line
			(start -0.2794 -0.1016)
			(end -0.2794 0.9906)
			(stroke
				(width 0.1)
				(type default)
			)
			(layer "F.Fab")
		)
		(fp_line
			(start 0.2794 -0.1016)
			(end -0.2794 -0.1016)
			(stroke
				(width 0.1)
				(type default)
			)
			(layer "F.Fab")
		)
		(pad "1" smd rect
			(at 0 0 270)
			(size 0.508 0.508)
			(layers "F.Cu" "F.Mask" "F.Paste")
			(net "P3V3_STBY")
		)
		(pad "2" smd rect
			(at 0 0.889 270)
			(size 0.508 0.508)
			(layers "F.Cu" "F.Mask" "F.Paste")
			(net "PWRGD_P2V5_BMC_STBY_R")
		)
		(zone
			(layer "F.Cu")
			(hatch none 0.5)
			(connect_pads
				(clearance 0)
			)
			(min_thickness 0.25)
			(keepout
				(tracks not_allowed)
				(vias allowed)
				(pads allowed)
				(copperpour not_allowed)
				(footprints allowed)
			)
			(placement
				(enabled no)
				(sheetname "")
			)
			(fill
				(thermal_gap 0.5)
				(thermal_bridge_width 0.5)
				(island_removal_mode 0)
			)
			(polygon
				(pts
					(xy 450.088 -20.5232) (xy 450.088 -20.0152) (xy 450.469 -20.0152) (xy 450.469 -20.5232)
				)
			)
		)
		(zone
			(layer "F.Cu")
			(hatch none 0.5)
			(connect_pads
				(clearance 0)
			)
			(min_thickness 0.25)
			(keepout
				(tracks allowed)
				(vias not_allowed)
				(pads allowed)
				(copperpour not_allowed)
				(footprints allowed)
			)
			(placement
				(enabled no)
				(sheetname "")
			)
			(fill
				(thermal_gap 0.5)
				(thermal_bridge_width 0.5)
				(island_removal_mode 0)
			)
			(polygon
				(pts
					(xy 450.469 -20.5232) (xy 450.469 -20.0152) (xy 450.088 -20.0152) (xy 450.088 -20.5232)
				)
			)
		)
	)
	(footprint ""
		(layer "F.Cu")
		(at 367.922556 -156.250894 180)
		(property "Reference" "C22W25"
			(at 0 0 180)
			(layer "F.SilkS")
			(hide yes)
			(effects
				(font
					(size 1.27 1.27)
				)
			)
		)
		(property "Value" "*"
			(at -0.0762 -6.2357 180)
			(unlocked yes)
			(layer "F.Fab")
			(hide yes)
			(effects
				(font
					(size 1.27 1.016)
					(thickness 0.1524)
				)
			)
		)
		(property "Device Type" "SC22U16V5MX-4-GP_SMD-BCG5-SC22A"
			(at -0.0762 -8.2677 180)
			(unlocked yes)
			(layer "F.Fab")
			(hide yes)
			(effects
				(font
					(size 1.27 1.016)
					(thickness 0.1524)
				)
			)
		)
		(duplicate_pad_numbers_are_jumpers no)
		(fp_line
			(start 0.635 0)
			(end -0.635 0)
			(stroke
				(width 0.508)
				(type default)
			)
			(layer "F.SilkS")
		)
		(fp_rect
			(start -0.9652 1.778)
			(end 0.9652 -1.778)
			(stroke
				(width 0)
				(type default)
			)
			(fill no)
			(layer "F.CrtYd")
		)
		(fp_poly
			(pts
				(xy -0.9652 -1.778) (xy 0.9652 -1.778) (xy 0.9652 1.778) (xy -0.9652 1.778)
			)
			(stroke
				(width 0)
				(type default)
			)
			(fill no)
			(layer "F.Fab")
		)
		(pad "1" smd rect
			(at 0 -0.9652 180)
			(size 1.397 1.143)
			(layers "F.Cu" "F.Mask" "F.Paste")
			(net "VR_FET_SW_P12V_STBY_PVDDQ_DEF")
		)
		(pad "2" smd rect
			(at 0 0.9652 180)
			(size 1.397 1.143)
			(layers "F.Cu" "F.Mask" "F.Paste")
			(net "GND")
		)
	)
	(footprint ""
		(layer "F.Cu")
		(at 161.6456 -64.897 180)
		(property "Reference" "C3D27"
			(at 0 0 180)
			(layer "F.SilkS")
			(hide yes)
			(effects
				(font
					(size 1.27 1.27)
				)
			)
		)
		(property "Value" ""
			(at 0 0 180)
			(layer "F.Fab")
			(effects
				(font
					(size 1.27 1.27)
				)
			)
		)
		(duplicate_pad_numbers_are_jumpers no)
		(fp_poly
			(pts
				(xy 0.3048 -0.1016) (xy 0.3048 0.9906) (xy -0.3048 0.9906) (xy -0.3048 -0.1016)
			)
			(stroke
				(width 0)
				(type default)
			)
			(fill no)
			(layer "F.CrtYd")
		)
		(fp_line
			(start 0.3048 0.9906)
			(end 0.3048 -0.1016)
			(stroke
				(width 0.1)
				(type default)
			)
			(layer "F.Fab")
		)
		(fp_line
			(start 0.3048 -0.1016)
			(end -0.3048 -0.1016)
			(stroke
				(width 0.1)
				(type default)
			)
			(layer "F.Fab")
		)
		(fp_line
			(start -0.3048 0.9906)
			(end 0.3048 0.9906)
			(stroke
				(width 0.1)
				(type default)
			)
			(layer "F.Fab")
		)
		(fp_line
			(start -0.3048 -0.1016)
			(end -0.3048 0.9906)
			(stroke
				(width 0.1)
				(type default)
			)
			(layer "F.Fab")
		)
		(pad "1" smd rect
			(at 0 0 180)
			(size 0.508 0.508)
			(layers "F.Cu" "F.Mask" "F.Paste")
			(net "VSENSE_PVCCIO_CPU1_SKT_VSEN")
		)
		(pad "2" smd rect
			(at 0 0.889 180)
			(size 0.508 0.508)
			(layers "F.Cu" "F.Mask" "F.Paste")
			(net "VSENSE_PVCCIO_CPU1_SKT_VRTN")
		)
		(zone
			(layer "F.Cu")
			(hatch none 0.5)
			(connect_pads
				(clearance 0)
			)
			(min_thickness 0.25)
			(keepout
				(tracks not_allowed)
				(vias allowed)
				(pads allowed)
				(copperpour not_allowed)
				(footprints allowed)
			)
			(placement
				(enabled no)
				(sheetname "")
			)
			(fill
				(thermal_gap 0.5)
				(thermal_bridge_width 0.5)
				(island_removal_mode 0)
			)
			(polygon
				(pts
					(xy 161.8996 -65.532) (xy 161.3916 -65.532) (xy 161.3916 -65.151) (xy 161.8996 -65.151)
				)
			)
		)
		(zone
			(layer "F.Cu")
			(hatch none 0.5)
			(connect_pads
				(clearance 0)
			)
			(min_thickness 0.25)
			(keepout
				(tracks allowed)
				(vias not_allowed)
				(pads allowed)
				(copperpour not_allowed)
				(footprints allowed)
			)
			(placement
				(enabled no)
				(sheetname "")
			)
			(fill
				(thermal_gap 0.5)
				(thermal_bridge_width 0.5)
				(island_removal_mode 0)
			)
			(polygon
				(pts
					(xy 161.8996 -65.151) (xy 161.3916 -65.151) (xy 161.3916 -65.532) (xy 161.8996 -65.532)
				)
			)
		)
	)
)
